(kicad_pcb
	(version 20260206)
	(generator "pcbnew")
	(generator_version "10.0")
	(general
		(thickness 1.6)
		(legacy_teardrops no)
	)
	(paper "A4")
	(title_block
		(title "04192023_DAF0TMB3IC0_F0TG_MB_C_brd_V02_OCP.brd")
		(comment 1 "Grand Teton / footprints 8029-8036 of 8354")
	)
	(layers
		(0 "F.Cu" signal "TOP")
		(4 "In1.Cu" signal "GND")
		(6 "In2.Cu" signal "IN1")
		(8 "In3.Cu" signal "GND1")
		(10 "In4.Cu" signal "IN2")
		(12 "In5.Cu" signal "GND2")
		(14 "In6.Cu" signal "IN3")
		(16 "In7.Cu" signal "GND3")
		(18 "In8.Cu" signal "VCC")
		(20 "In9.Cu" signal "VCC1")
		(22 "In10.Cu" signal "GND4")
		(24 "In11.Cu" signal "IN4")
		(26 "In12.Cu" signal "GND5")
		(28 "In13.Cu" signal "IN5")
		(30 "In14.Cu" signal "GND6")
		(32 "In15.Cu" signal "IN6")
		(34 "In16.Cu" signal "GND7")
		(2 "B.Cu" signal "BOTTOM")
		(9 "F.Adhes" user "F.Adhesive")
		(11 "B.Adhes" user "B.Adhesive")
		(13 "F.Paste" user "Package Geometry/Pastemask Top")
		(15 "B.Paste" user "Package Geometry/Pastemask Bottom")
		(5 "F.SilkS" user "Ref Des/Silkscreen Top")
		(7 "B.SilkS" user "Ref Des/Silkscreen Bottom")
		(1 "F.Mask" user "Board Geometry/Soldermask Top")
		(3 "B.Mask" user "Board Geometry/Soldermask Bottom")
		(17 "Dwgs.User" user "User.Drawings")
		(19 "Cmts.User" user "User.Comments")
		(21 "Eco1.User" user "User.Eco1")
		(23 "Eco2.User" user "User.Eco2")
		(25 "Edge.Cuts" user "Board Geometry/Outline")
		(27 "Margin" user)
		(31 "F.CrtYd" user "Package Geometry/Place Bound Top")
		(29 "B.CrtYd" user "Package Geometry/Place Bound Bottom")
		(35 "F.Fab" user "Ref Des/Assembly Top")
		(33 "B.Fab" user "Ref Des/Assembly Bottom")
	)
	(footprint ""
		(layer "B.Cu")
		(at 37.565076 -339.915754 -90)
		(property "Reference" "PC452"
			(at 9.447276 1.051814 270)
			(unlocked yes)
			(layer "B.SilkS")
			(effects
				(font
					(size 0.7874 0.5842)
					(thickness 0.1524)
				)
				(justify left mirror)
			)
		)
		(property "Value" ""
			(at 0 0 90)
			(layer "B.Fab")
			(effects
				(font
					(size 1.27 1.27)
				)
				(justify mirror)
			)
		)
		(duplicate_pad_numbers_are_jumpers no)
		(fp_line
			(start -4.533392 2.249932)
			(end 4.533392 2.249932)
			(stroke
				(width 0.1524)
				(type default)
			)
			(layer "B.SilkS")
		)
		(fp_line
			(start 4.533392 2.249932)
			(end 4.533392 -2.249932)
			(stroke
				(width 0.1524)
				(type default)
			)
			(layer "B.SilkS")
		)
		(fp_line
			(start -4.533392 -2.249932)
			(end -4.533392 2.249932)
			(stroke
				(width 0.1524)
				(type default)
			)
			(layer "B.SilkS")
		)
		(fp_line
			(start 4.533392 -2.249932)
			(end -4.533392 -2.249932)
			(stroke
				(width 0.1524)
				(type default)
			)
			(layer "B.SilkS")
		)
		(fp_rect
			(start 5.39242 2.326132)
			(end 4.533392 -2.326132)
			(stroke
				(width 0)
				(type default)
			)
			(fill yes)
			(layer "B.SilkS")
		)
		(fp_line
			(start -3.750056 2.249932)
			(end 3.750056 2.249932)
			(stroke
				(width 0.1)
				(type default)
			)
			(layer "B.Fab")
		)
		(fp_line
			(start 3.750056 2.249932)
			(end 3.750056 -2.249932)
			(stroke
				(width 0.1)
				(type default)
			)
			(layer "B.Fab")
		)
		(fp_line
			(start -3.750056 -2.249932)
			(end -3.750056 2.249932)
			(stroke
				(width 0.1)
				(type default)
			)
			(layer "B.Fab")
		)
		(fp_line
			(start 3.750056 -2.249932)
			(end -3.750056 -2.249932)
			(stroke
				(width 0.1)
				(type default)
			)
			(layer "B.Fab")
		)
		(fp_text user "+"
			(at 6.322314 0.786384 180)
			(unlocked yes)
			(layer "B.SilkS")
			(effects
				(font
					(size 1.905 1.4224)
					(thickness 0.1524)
				)
				(justify left mirror)
			)
		)
		(fp_text user "-"
			(at -4.27736 -1.846072 270)
			(unlocked yes)
			(layer "B.SilkS")
			(effects
				(font
					(size 1.905 1.4224)
					(thickness 0.1524)
				)
				(justify left mirror)
			)
		)
		(fp_text user "+"
			(at 6.322314 0.786384 180)
			(unlocked yes)
			(layer "B.Fab")
			(effects
				(font
					(size 1.905 1.4224)
					(thickness 0.1524)
				)
				(justify left mirror)
			)
		)
		(fp_text user "-"
			(at -4.8514 -0.14605 270)
			(unlocked yes)
			(layer "B.Fab")
			(effects
				(font
					(size 1.905 1.4224)
					(thickness 0.1524)
				)
				(justify left mirror)
			)
		)
		(pad "1" smd rect
			(at 3.199892 0 90)
			(size 2.413 2.8194)
			(layers "B.Cu" "B.Mask" "B.Paste")
			(net "PVDDIO_P1")
		)
		(pad "2" smd rect
			(at -3.199892 0 90)
			(size 2.413 2.8194)
			(layers "B.Cu" "B.Mask" "B.Paste")
			(net "GND")
		)
	)
	(footprint ""
		(layer "B.Cu")
		(at 112.624108 -381.321818)
		(property "Reference" "C7031"
			(at 0 0 0)
			(layer "B.SilkS")
			(hide yes)
			(effects
				(font
					(size 1.27 1.27)
				)
				(justify mirror)
			)
		)
		(property "Value" ""
			(at 0 0 0)
			(layer "B.Fab")
			(effects
				(font
					(size 1.27 1.27)
				)
				(justify mirror)
			)
		)
		(duplicate_pad_numbers_are_jumpers no)
		(fp_line
			(start -1.524 -0.762)
			(end -1.524 0.762)
			(stroke
				(width 0.1524)
				(type default)
			)
			(layer "B.SilkS")
		)
		(fp_line
			(start -1.524 0.762)
			(end 1.524 0.762)
			(stroke
				(width 0.1524)
				(type default)
			)
			(layer "B.SilkS")
		)
		(fp_line
			(start 1.524 -0.762)
			(end -1.524 -0.762)
			(stroke
				(width 0.1524)
				(type default)
			)
			(layer "B.SilkS")
		)
		(fp_line
			(start 1.524 0.762)
			(end 1.524 -0.762)
			(stroke
				(width 0.1524)
				(type default)
			)
			(layer "B.SilkS")
		)
		(fp_line
			(start -1.1049 -0.724916)
			(end 1.1049 -0.724916)
			(stroke
				(width 0.1)
				(type default)
			)
			(layer "B.Fab")
		)
		(fp_line
			(start -1.1049 0.724916)
			(end -1.1049 -0.724916)
			(stroke
				(width 0.1)
				(type default)
			)
			(layer "B.Fab")
		)
		(fp_line
			(start 1.1049 -0.724916)
			(end 1.1049 0.724916)
			(stroke
				(width 0.1)
				(type default)
			)
			(layer "B.Fab")
		)
		(fp_line
			(start 1.1049 0.724916)
			(end -1.1049 0.724916)
			(stroke
				(width 0.1)
				(type default)
			)
			(layer "B.Fab")
		)
		(pad "1" smd rect
			(at 0.889 0)
			(size 1.016 1.27)
			(layers "B.Cu" "B.Mask" "B.Paste")
			(net "P0V9_CPU1_RT3_2A")
		)
		(pad "2" smd rect
			(at -0.889 0)
			(size 1.016 1.27)
			(layers "B.Cu" "B.Mask" "B.Paste")
			(net "GND")
		)
	)
	(footprint ""
		(layer "B.Cu")
		(at 179.516278 -192.66027 180)
		(property "Reference" "C534"
			(at 0 0 0)
			(layer "B.SilkS")
			(hide yes)
			(effects
				(font
					(size 1.27 1.27)
				)
				(justify mirror)
			)
		)
		(property "Value" ""
			(at 0 0 0)
			(layer "B.Fab")
			(effects
				(font
					(size 1.27 1.27)
				)
				(justify mirror)
			)
		)
		(duplicate_pad_numbers_are_jumpers no)
		(fp_line
			(start 1.524 0.762)
			(end 1.524 -0.762)
			(stroke
				(width 0.1524)
				(type default)
			)
			(layer "B.SilkS")
		)
		(fp_line
			(start 1.524 -0.762)
			(end -1.524 -0.762)
			(stroke
				(width 0.1524)
				(type default)
			)
			(layer "B.SilkS")
		)
		(fp_line
			(start -1.524 0.762)
			(end 1.524 0.762)
			(stroke
				(width 0.1524)
				(type default)
			)
			(layer "B.SilkS")
		)
		(fp_line
			(start -1.524 -0.762)
			(end -1.524 0.762)
			(stroke
				(width 0.1524)
				(type default)
			)
			(layer "B.SilkS")
		)
		(fp_line
			(start 1.1049 0.724916)
			(end -1.1049 0.724916)
			(stroke
				(width 0.1)
				(type default)
			)
			(layer "B.Fab")
		)
		(fp_line
			(start 1.1049 -0.724916)
			(end 1.1049 0.724916)
			(stroke
				(width 0.1)
				(type default)
			)
			(layer "B.Fab")
		)
		(fp_line
			(start -1.1049 0.724916)
			(end -1.1049 -0.724916)
			(stroke
				(width 0.1)
				(type default)
			)
			(layer "B.Fab")
		)
		(fp_line
			(start -1.1049 -0.724916)
			(end 1.1049 -0.724916)
			(stroke
				(width 0.1)
				(type default)
			)
			(layer "B.Fab")
		)
		(pad "1" smd rect
			(at 0.889 0 180)
			(size 1.016 1.27)
			(layers "B.Cu" "B.Mask" "B.Paste")
			(net "P12V_MEM_CPU1")
		)
		(pad "2" smd rect
			(at -0.889 0 180)
			(size 1.016 1.27)
			(layers "B.Cu" "B.Mask" "B.Paste")
			(net "GND")
		)
	)
	(footprint ""
		(layer "B.Cu")
		(at 413.304736 -159.989012 90)
		(property "Reference" "PC611_3"
			(at 0 0 90)
			(layer "B.SilkS")
			(hide yes)
			(effects
				(font
					(size 1.27 1.27)
				)
				(justify mirror)
			)
		)
		(property "Value" ""
			(at 0 0 90)
			(layer "B.Fab")
			(effects
				(font
					(size 1.27 1.27)
				)
				(justify mirror)
			)
		)
		(duplicate_pad_numbers_are_jumpers no)
		(fp_line
			(start 1.524 -0.762)
			(end -1.524 -0.762)
			(stroke
				(width 0.1524)
				(type default)
			)
			(layer "B.SilkS")
		)
		(fp_line
			(start -1.524 -0.762)
			(end -1.524 0.762)
			(stroke
				(width 0.1524)
				(type default)
			)
			(layer "B.SilkS")
		)
		(fp_line
			(start 1.524 0.762)
			(end 1.524 -0.762)
			(stroke
				(width 0.1524)
				(type default)
			)
			(layer "B.SilkS")
		)
		(fp_line
			(start -1.524 0.762)
			(end 1.524 0.762)
			(stroke
				(width 0.1524)
				(type default)
			)
			(layer "B.SilkS")
		)
		(fp_line
			(start 1.1049 -0.724916)
			(end 1.1049 0.724916)
			(stroke
				(width 0.1)
				(type default)
			)
			(layer "B.Fab")
		)
		(fp_line
			(start -1.1049 -0.724916)
			(end 1.1049 -0.724916)
			(stroke
				(width 0.1)
				(type default)
			)
			(layer "B.Fab")
		)
		(fp_line
			(start 1.1049 0.724916)
			(end -1.1049 0.724916)
			(stroke
				(width 0.1)
				(type default)
			)
			(layer "B.Fab")
		)
		(fp_line
			(start -1.1049 0.724916)
			(end -1.1049 -0.724916)
			(stroke
				(width 0.1)
				(type default)
			)
			(layer "B.Fab")
		)
		(pad "1" smd rect
			(at 0.889 0 90)
			(size 1.016 1.27)
			(layers "B.Cu" "B.Mask" "B.Paste")
			(net "SW_P12V_AUX_PVDDCR_SOC_P0_FLT")
		)
		(pad "2" smd rect
			(at -0.889 0 90)
			(size 1.016 1.27)
			(layers "B.Cu" "B.Mask" "B.Paste")
			(net "GND")
		)
	)
	(footprint ""
		(layer "B.Cu")
		(at 234.80522 -325.894192 180)
		(property "Reference" "R1223"
			(at 0 0 0)
			(layer "B.SilkS")
			(hide yes)
			(effects
				(font
					(size 1.27 1.27)
				)
				(justify mirror)
			)
		)
		(property "Value" ""
			(at 0 0 0)
			(layer "B.Fab")
			(effects
				(font
					(size 1.27 1.27)
				)
				(justify mirror)
			)
		)
		(duplicate_pad_numbers_are_jumpers no)
		(fp_line
			(start 0.7874 0.4064)
			(end 0.7874 -0.4064)
			(stroke
				(width 0.1524)
				(type default)
			)
			(layer "B.SilkS")
		)
		(fp_line
			(start 0.7874 -0.4064)
			(end -0.7874 -0.4064)
			(stroke
				(width 0.1524)
				(type default)
			)
			(layer "B.SilkS")
		)
		(fp_line
			(start -0.7874 0.4064)
			(end 0.7874 0.4064)
			(stroke
				(width 0.1524)
				(type default)
			)
			(layer "B.SilkS")
		)
		(fp_line
			(start -0.7874 -0.4064)
			(end -0.7874 0.4064)
			(stroke
				(width 0.1524)
				(type default)
			)
			(layer "B.SilkS")
		)
		(fp_line
			(start 0.67945 0.3048)
			(end 0.67945 -0.305054)
			(stroke
				(width 0.1)
				(type default)
			)
			(layer "B.Fab")
		)
		(fp_line
			(start 0.67945 -0.305054)
			(end 0.12065 -0.305054)
			(stroke
				(width 0.1)
				(type default)
			)
			(layer "B.Fab")
		)
		(fp_line
			(start 0.12065 0.3048)
			(end 0.67945 0.3048)
			(stroke
				(width 0.1)
				(type default)
			)
			(layer "B.Fab")
		)
		(fp_line
			(start 0.12065 0.2794)
			(end 0.12065 0.3048)
			(stroke
				(width 0.1)
				(type default)
			)
			(layer "B.Fab")
		)
		(fp_line
			(start 0.12065 -0.2794)
			(end -0.12065 -0.2794)
			(stroke
				(width 0.1)
				(type default)
			)
			(layer "B.Fab")
		)
		(fp_line
			(start 0.12065 -0.305054)
			(end 0.12065 -0.2794)
			(stroke
				(width 0.1)
				(type default)
			)
			(layer "B.Fab")
		)
		(fp_line
			(start -0.120396 0.3048)
			(end -0.120396 0.2794)
			(stroke
				(width 0.1)
				(type default)
			)
			(layer "B.Fab")
		)
		(fp_line
			(start -0.120396 0.2794)
			(end 0.12065 0.2794)
			(stroke
				(width 0.1)
				(type default)
			)
			(layer "B.Fab")
		)
		(fp_line
			(start -0.12065 -0.2794)
			(end -0.12065 -0.3048)
			(stroke
				(width 0.1)
				(type default)
			)
			(layer "B.Fab")
		)
		(fp_line
			(start -0.12065 -0.3048)
			(end -0.67945 -0.3048)
			(stroke
				(width 0.1)
				(type default)
			)
			(layer "B.Fab")
		)
		(fp_line
			(start -0.67945 0.3048)
			(end -0.120396 0.3048)
			(stroke
				(width 0.1)
				(type default)
			)
			(layer "B.Fab")
		)
		(fp_line
			(start -0.67945 -0.3048)
			(end -0.67945 0.3048)
			(stroke
				(width 0.1)
				(type default)
			)
			(layer "B.Fab")
		)
		(pad "1" smd circle
			(at 0.40005 0)
			(size 0 0)
			(layers "B.Cu" "B.Mask" "B.Paste")
			(net "P1V8_CPU1_RT_1D_ADC")
		)
		(pad "2" smd circle
			(at -0.40005 0)
			(size 0 0)
			(layers "B.Cu" "B.Mask" "B.Paste")
			(net "GND")
		)
	)
	(footprint ""
		(layer "B.Cu")
		(at 361.046014 -259.845048 180)
		(property "Reference" "C2160"
			(at 0 0 0)
			(layer "B.SilkS")
			(hide yes)
			(effects
				(font
					(size 1.27 1.27)
				)
				(justify mirror)
			)
		)
		(property "Value" ""
			(at 0 0 0)
			(layer "B.Fab")
			(effects
				(font
					(size 1.27 1.27)
				)
				(justify mirror)
			)
		)
		(duplicate_pad_numbers_are_jumpers no)
		(fp_line
			(start 0.7874 0.4064)
			(end 0.7874 -0.4064)
			(stroke
				(width 0.1524)
				(type default)
			)
			(layer "B.SilkS")
		)
		(fp_line
			(start 0.7874 -0.4064)
			(end -0.7874 -0.4064)
			(stroke
				(width 0.1524)
				(type default)
			)
			(layer "B.SilkS")
		)
		(fp_line
			(start -0.7874 0.4064)
			(end 0.7874 0.4064)
			(stroke
				(width 0.1524)
				(type default)
			)
			(layer "B.SilkS")
		)
		(fp_line
			(start -0.7874 -0.4064)
			(end -0.7874 0.4064)
			(stroke
				(width 0.1524)
				(type default)
			)
			(layer "B.SilkS")
		)
		(fp_line
			(start 0.67945 0.3048)
			(end 0.67945 -0.305054)
			(stroke
				(width 0.1)
				(type default)
			)
			(layer "B.Fab")
		)
		(fp_line
			(start 0.67945 -0.305054)
			(end 0.12065 -0.305054)
			(stroke
				(width 0.1)
				(type default)
			)
			(layer "B.Fab")
		)
		(fp_line
			(start 0.12065 0.3048)
			(end 0.67945 0.3048)
			(stroke
				(width 0.1)
				(type default)
			)
			(layer "B.Fab")
		)
		(fp_line
			(start 0.12065 0.2794)
			(end 0.12065 0.3048)
			(stroke
				(width 0.1)
				(type default)
			)
			(layer "B.Fab")
		)
		(fp_line
			(start 0.12065 -0.2794)
			(end -0.12065 -0.2794)
			(stroke
				(width 0.1)
				(type default)
			)
			(layer "B.Fab")
		)
		(fp_line
			(start 0.12065 -0.305054)
			(end 0.12065 -0.2794)
			(stroke
				(width 0.1)
				(type default)
			)
			(layer "B.Fab")
		)
		(fp_line
			(start -0.120396 0.3048)
			(end -0.120396 0.2794)
			(stroke
				(width 0.1)
				(type default)
			)
			(layer "B.Fab")
		)
		(fp_line
			(start -0.120396 0.2794)
			(end 0.12065 0.2794)
			(stroke
				(width 0.1)
				(type default)
			)
			(layer "B.Fab")
		)
		(fp_line
			(start -0.12065 -0.2794)
			(end -0.12065 -0.3048)
			(stroke
				(width 0.1)
				(type default)
			)
			(layer "B.Fab")
		)
		(fp_line
			(start -0.12065 -0.3048)
			(end -0.67945 -0.3048)
			(stroke
				(width 0.1)
				(type default)
			)
			(layer "B.Fab")
		)
		(fp_line
			(start -0.67945 0.3048)
			(end -0.120396 0.3048)
			(stroke
				(width 0.1)
				(type default)
			)
			(layer "B.Fab")
		)
		(fp_line
			(start -0.67945 -0.3048)
			(end -0.67945 0.3048)
			(stroke
				(width 0.1)
				(type default)
			)
			(layer "B.Fab")
		)
		(pad "1" smd circle
			(at 0.40005 0)
			(size 0 0)
			(layers "B.Cu" "B.Mask" "B.Paste")
			(net "PVDD11_S3_P0")
		)
		(pad "2" smd circle
			(at -0.40005 0)
			(size 0 0)
			(layers "B.Cu" "B.Mask" "B.Paste")
			(net "GND")
		)
	)
	(footprint ""
		(layer "B.Cu")
		(at 298.526454 -190.82131 180)
		(property "Reference" "R88"
			(at 0 0 0)
			(layer "B.SilkS")
			(hide yes)
			(effects
				(font
					(size 1.27 1.27)
				)
				(justify mirror)
			)
		)
		(property "Value" ""
			(at 0 0 0)
			(layer "B.Fab")
			(effects
				(font
					(size 1.27 1.27)
				)
				(justify mirror)
			)
		)
		(duplicate_pad_numbers_are_jumpers no)
		(fp_line
			(start 0.7874 0.4064)
			(end 0.7874 -0.4064)
			(stroke
				(width 0.1524)
				(type default)
			)
			(layer "B.SilkS")
		)
		(fp_line
			(start 0.7874 -0.4064)
			(end -0.7874 -0.4064)
			(stroke
				(width 0.1524)
				(type default)
			)
			(layer "B.SilkS")
		)
		(fp_line
			(start -0.7874 0.4064)
			(end 0.7874 0.4064)
			(stroke
				(width 0.1524)
				(type default)
			)
			(layer "B.SilkS")
		)
		(fp_line
			(start -0.7874 -0.4064)
			(end -0.7874 0.4064)
			(stroke
				(width 0.1524)
				(type default)
			)
			(layer "B.SilkS")
		)
		(fp_line
			(start 0.67945 0.3048)
			(end 0.67945 -0.305054)
			(stroke
				(width 0.1)
				(type default)
			)
			(layer "B.Fab")
		)
		(fp_line
			(start 0.67945 -0.305054)
			(end 0.12065 -0.305054)
			(stroke
				(width 0.1)
				(type default)
			)
			(layer "B.Fab")
		)
		(fp_line
			(start 0.12065 0.3048)
			(end 0.67945 0.3048)
			(stroke
				(width 0.1)
				(type default)
			)
			(layer "B.Fab")
		)
		(fp_line
			(start 0.12065 0.2794)
			(end 0.12065 0.3048)
			(stroke
				(width 0.1)
				(type default)
			)
			(layer "B.Fab")
		)
		(fp_line
			(start 0.12065 -0.2794)
			(end -0.12065 -0.2794)
			(stroke
				(width 0.1)
				(type default)
			)
			(layer "B.Fab")
		)
		(fp_line
			(start 0.12065 -0.305054)
			(end 0.12065 -0.2794)
			(stroke
				(width 0.1)
				(type default)
			)
			(layer "B.Fab")
		)
		(fp_line
			(start -0.120396 0.3048)
			(end -0.120396 0.2794)
			(stroke
				(width 0.1)
				(type default)
			)
			(layer "B.Fab")
		)
		(fp_line
			(start -0.120396 0.2794)
			(end 0.12065 0.2794)
			(stroke
				(width 0.1)
				(type default)
			)
			(layer "B.Fab")
		)
		(fp_line
			(start -0.12065 -0.2794)
			(end -0.12065 -0.3048)
			(stroke
				(width 0.1)
				(type default)
			)
			(layer "B.Fab")
		)
		(fp_line
			(start -0.12065 -0.3048)
			(end -0.67945 -0.3048)
			(stroke
				(width 0.1)
				(type default)
			)
			(layer "B.Fab")
		)
		(fp_line
			(start -0.67945 0.3048)
			(end -0.120396 0.3048)
			(stroke
				(width 0.1)
				(type default)
			)
			(layer "B.Fab")
		)
		(fp_line
			(start -0.67945 -0.3048)
			(end -0.67945 0.3048)
			(stroke
				(width 0.1)
				(type default)
			)
			(layer "B.Fab")
		)
		(pad "1" smd circle
			(at 0.40005 0)
			(size 0 0)
			(layers "B.Cu" "B.Mask" "B.Paste")
			(net "P3V3")
		)
		(pad "2" smd circle
			(at -0.40005 0)
			(size 0 0)
			(layers "B.Cu" "B.Mask" "B.Paste")
			(net "PWRGD_CHAF_CPU0")
		)
	)
	(footprint ""
		(layer "B.Cu")
		(at 255.905 -337.37804 180)
		(property "Reference" "R830"
			(at 0 0 0)
			(layer "B.SilkS")
			(hide yes)
			(effects
				(font
					(size 1.27 1.27)
				)
				(justify mirror)
			)
		)
		(property "Value" ""
			(at 0 0 0)
			(layer "B.Fab")
			(effects
				(font
					(size 1.27 1.27)
				)
				(justify mirror)
			)
		)
		(duplicate_pad_numbers_are_jumpers no)
		(fp_line
			(start 0.32512 0.175006)
			(end 0.32512 -0.175006)
			(stroke
				(width 0.1)
				(type default)
			)
			(layer "B.Fab")
		)
		(fp_line
			(start 0.32512 -0.175006)
			(end -0.32512 -0.175006)
			(stroke
				(width 0.1)
				(type default)
			)
			(layer "B.Fab")
		)
		(fp_line
			(start -0.32512 0.175006)
			(end 0.32512 0.175006)
			(stroke
				(width 0.1)
				(type default)
			)
			(layer "B.Fab")
		)
		(fp_line
			(start -0.32512 -0.175006)
			(end -0.32512 0.175006)
			(stroke
				(width 0.1)
				(type default)
			)
			(layer "B.Fab")
		)
		(pad "1" smd rect
			(at 0.2667 0)
			(size 0.3048 0.381)
			(layers "B.Cu" "B.Mask" "B.Paste")
			(net "SMB_RT_CPU0_P3_ROM_MUX_2D_R_SDA")
		)
		(pad "2" smd rect
			(at -0.2667 0 180)
			(size 0.3048 0.381)
			(layers "B.Cu" "B.Mask" "B.Paste")
			(net "SMB_RT_CPU0_P3_ROM_MUX_2D_SDA")
		)
	)
)
